# T6G (Grand Teton) — schematic netlist excerpt (pin names and nets, part order shuffled) for the footprints in the layout excerpt that follows; sources: Cadence DE-HDL packaged netlist, KiCad conversion of 04192023_DAF0TMB3IC0_F0TG_MB_C_brd_V02_OCP.brd

PU29  ISL99390FRZTR5935  ISL99390FRZ-TR5935 IC  pkg QFN21_6X5XB  page 213
  VOS  = PVDDCR_CPU0_P1_VOS5
  AGND  = GND
  VCC  = PVDDCR_CPU0_P1_VCC5
  PVCC  = PVDDCR_CPU0_P1_PVCC
  PGND1  = GND
  GL1  = NC_PVDDCR_CPU0_P1_GL1_5
  PGND2  = GND
  SW  = SW_PVDDCR_CPU0_P1_SW5
  VIN1  = SW_P12V_AUX_PVDDCR_CPU0_P1_FLT
  VIN2  = SW_P12V_AUX_PVDDCR_CPU0_P1_FLT
  DNC  = NC_PVDDCR_CPU0_P1_DNC5
  PHASE  = SW_PVDDCR_CPU0_P1_PH5
  BOOT  = SW_PVDDCR_CPU0_P1_BOOT5
  PWM  = PVDDCR_CPU0_P1_PWM5
  EN  = PVDDCR_CPU0_P1_VCC5
  TOUT_FLT  = PVDDCR_CPU0_P1_TEMP0
  LSET  = PVDDCR_CPU0_P1_LSET5
  IOUT  = PVDDCR_CPU0_P1_IMON5
  REFIN  = PVDDCR_CPU0_P1_VCCS
  PGND3  = GND
  GL2  = NC_PVDDCR_CPU0_P1_GL2_5

(kicad_pcb
	(version 20260206)
	(generator "pcbnew")
	(generator_version "10.0")
	(general
		(thickness 1.6)
		(legacy_teardrops no)
	)
	(paper "A4")
	(title_block
		(title "04192023_DAF0TMB3IC0_F0TG_MB_C_brd_V02_OCP.brd")
		(comment 1 "Grand Teton / footprints 3172-3172 of 8354")
	)
	(layers
		(0 "F.Cu" signal "TOP")
		(4 "In1.Cu" signal "GND")
		(6 "In2.Cu" signal "IN1")
		(8 "In3.Cu" signal "GND1")
		(10 "In4.Cu" signal "IN2")
		(12 "In5.Cu" signal "GND2")
		(14 "In6.Cu" signal "IN3")
		(16 "In7.Cu" signal "GND3")
		(18 "In8.Cu" signal "VCC")
		(20 "In9.Cu" signal "VCC1")
		(22 "In10.Cu" signal "GND4")
		(24 "In11.Cu" signal "IN4")
		(26 "In12.Cu" signal "GND5")
		(28 "In13.Cu" signal "IN5")
		(30 "In14.Cu" signal "GND6")
		(32 "In15.Cu" signal "IN6")
		(34 "In16.Cu" signal "GND7")
		(2 "B.Cu" signal "BOTTOM")
		(9 "F.Adhes" user "F.Adhesive")
		(11 "B.Adhes" user "B.Adhesive")
		(13 "F.Paste" user "Package Geometry/Pastemask Top")
		(15 "B.Paste" user "Package Geometry/Pastemask Bottom")
		(5 "F.SilkS" user "Ref Des/Silkscreen Top")
		(7 "B.SilkS" user "Ref Des/Silkscreen Bottom")
		(1 "F.Mask" user "Board Geometry/Soldermask Top")
		(3 "B.Mask" user "Board Geometry/Soldermask Bottom")
		(17 "Dwgs.User" user "User.Drawings")
		(19 "Cmts.User" user "User.Comments")
		(21 "Eco1.User" user "User.Eco1")
		(23 "Eco2.User" user "User.Eco2")
		(25 "Edge.Cuts" user "Board Geometry/Outline")
		(27 "Margin" user)
		(31 "F.CrtYd" user "Package Geometry/Place Bound Top")
		(29 "B.CrtYd" user "Package Geometry/Place Bound Bottom")
		(35 "F.Fab" user "Ref Des/Assembly Top")
		(33 "B.Fab" user "Ref Des/Assembly Bottom")
	)
	(footprint ""
		(layer "F.Cu")
		(at 73.96099 -177.625756 180)
		(property "Reference" "PU29"
			(at -0.44958 -6.724142 0)
			(unlocked yes)
			(layer "F.SilkS")
			(effects
				(font
					(size 0.7874 0.5842)
					(thickness 0.1524)
				)
				(justify left)
			)
		)
		(property "Value" ""
			(at 0 0 180)
			(layer "F.Fab")
			(effects
				(font
					(size 1.27 1.27)
				)
			)
		)
		(duplicate_pad_numbers_are_jumpers no)
		(fp_line
			(start 2.500122 2.999994)
			(end 2.2987 2.999994)
			(stroke
				(width 0.1524)
				(type default)
			)
			(layer "F.SilkS")
		)
		(fp_line
			(start 2.500122 2.339594)
			(end 2.500122 2.999994)
			(stroke
				(width 0.1524)
				(type default)
			)
			(layer "F.SilkS")
		)
		(fp_line
			(start 2.500122 -2.999994)
			(end 2.500122 -2.44348)
			(stroke
				(width 0.1524)
				(type default)
			)
			(layer "F.SilkS")
		)
		(fp_line
			(start 2.31394 -2.999994)
			(end 2.500122 -2.999994)
			(stroke
				(width 0.1524)
				(type default)
			)
			(layer "F.SilkS")
		)
		(fp_line
			(start -2.2987 2.999994)
			(end -2.500122 2.999994)
			(stroke
				(width 0.1524)
				(type default)
			)
			(layer "F.SilkS")
		)
		(fp_line
			(start -2.500122 2.999994)
			(end -2.500122 2.339594)
			(stroke
				(width 0.1524)
				(type default)
			)
			(layer "F.SilkS")
		)
		(fp_line
			(start -2.500122 0.6604)
			(end -2.500122 0.229108)
			(stroke
				(width 0.1524)
				(type default)
			)
			(layer "F.SilkS")
		)
		(fp_line
			(start -2.500122 -2.529078)
			(end -2.500122 -2.999994)
			(stroke
				(width 0.1524)
				(type default)
			)
			(layer "F.SilkS")
		)
		(fp_line
			(start -2.500122 -2.999994)
			(end -2.24409 -2.999994)
			(stroke
				(width 0.1524)
				(type default)
			)
			(layer "F.SilkS")
		)
		(fp_poly
			(pts
				(xy -2.765298 -2.452878) (xy -3.438652 -2.677414) (xy -2.989834 -3.126232)
			)
			(stroke
				(width 0)
				(type default)
			)
			(fill yes)
			(layer "F.SilkS")
		)
		(fp_line
			(start 2.500122 2.999994)
			(end -2.500122 2.999994)
			(stroke
				(width 0.1)
				(type default)
			)
			(layer "F.Fab")
		)
		(fp_line
			(start 2.500122 -2.999994)
			(end 2.500122 2.999994)
			(stroke
				(width 0.1)
				(type default)
			)
			(layer "F.Fab")
		)
		(fp_line
			(start -2.500122 2.999994)
			(end -2.500122 -2.999994)
			(stroke
				(width 0.1)
				(type default)
			)
			(layer "F.Fab")
		)
		(fp_line
			(start -2.500122 -2.999994)
			(end 2.500122 -2.999994)
			(stroke
				(width 0.1)
				(type default)
			)
			(layer "F.Fab")
		)
		(fp_poly
			(pts
				(xy -4.218432 -2.783078) (xy -4.218432 -1.767078) (xy -3.202432 -2.275078)
			)
			(stroke
				(width 0)
				(type default)
			)
			(fill yes)
			(layer "F.Fab")
		)
		(pad "1" smd rect
			(at -2.400046 -2.275078 270)
			(size 0.2286 0.6096)
			(layers "F.Cu" "F.Mask" "F.Paste")
			(net "PVDDCR_CPU0_P1_VOS5")
		)
		(pad "2" smd rect
			(at -2.400046 -1.82499 270)
			(size 0.2286 0.6096)
			(layers "F.Cu" "F.Mask" "F.Paste")
			(net "GND")
		)
		(pad "3" smd rect
			(at -2.400046 -1.374902 270)
			(size 0.2286 0.6096)
			(layers "F.Cu" "F.Mask" "F.Paste")
			(net "PVDDCR_CPU0_P1_VCC5")
		)
		(pad "4" smd rect
			(at -2.400046 -0.925068 270)
			(size 0.2286 0.6096)
			(layers "F.Cu" "F.Mask" "F.Paste")
			(net "PVDDCR_CPU0_P1_PVCC")
		)
		(pad "5" smd rect
			(at -2.400046 -0.47498 270)
			(size 0.2286 0.6096)
			(layers "F.Cu" "F.Mask" "F.Paste")
			(net "GND")
		)
		(pad "6" smd rect
			(at -2.400046 -0.024892 270)
			(size 0.2286 0.6096)
			(layers "F.Cu" "F.Mask" "F.Paste")
			(net "NC_PVDDCR_CPU0_P1_GL1_5")
		)
		(pad "7_9-20_24" smd circle
			(at 0 1.150112 270)
			(size 0 0)
			(layers "F.Cu" "F.Mask" "F.Paste")
			(net "GND")
		)
		(pad "10_19" smd rect
			(at 0 2.899918 270)
			(size 0.6096 4.318)
			(layers "F.Cu" "F.Mask" "F.Paste")
			(net "SW_PVDDCR_CPU0_P1_SW5")
		)
		(pad "25_29" smd rect
			(at 1.549908 -1.279906 90)
			(size 2.0574 2.3114)
			(layers "F.Cu" "F.Mask" "F.Paste")
			(net "SW_P12V_AUX_PVDDCR_CPU0_P1_FLT")
		)
		(pad "30" smd rect
			(at 2.05994 -2.899918 180)
			(size 0.2286 0.6096)
			(layers "F.Cu" "F.Mask" "F.Paste")
			(net "SW_P12V_AUX_PVDDCR_CPU0_P1_FLT")
		)
		(pad "31" smd rect
			(at 1.610106 -2.899918 180)
			(size 0.2286 0.6096)
			(layers "F.Cu" "F.Mask" "F.Paste")
			(net "NC_PVDDCR_CPU0_P1_DNC5")
		)
		(pad "32" smd rect
			(at 1.160018 -2.899918 180)
			(size 0.2286 0.6096)
			(layers "F.Cu" "F.Mask" "F.Paste")
			(net "SW_PVDDCR_CPU0_P1_PH5")
		)
		(pad "33" smd rect
			(at 0.70993 -2.899918 180)
			(size 0.2286 0.6096)
			(layers "F.Cu" "F.Mask" "F.Paste")
			(net "SW_PVDDCR_CPU0_P1_BOOT5")
		)
		(pad "34" smd rect
			(at 0.260096 -2.899918 180)
			(size 0.2286 0.6096)
			(layers "F.Cu" "F.Mask" "F.Paste")
			(net "PVDDCR_CPU0_P1_PWM5")
		)
		(pad "35" smd rect
			(at -0.189992 -2.899918 180)
			(size 0.2286 0.6096)
			(layers "F.Cu" "F.Mask" "F.Paste")
			(net "PVDDCR_CPU0_P1_VCC5")
		)
		(pad "36" smd rect
			(at -0.64008 -2.899918 180)
			(size 0.2286 0.6096)
			(layers "F.Cu" "F.Mask" "F.Paste")
			(net "PVDDCR_CPU0_P1_TEMP0")
		)
		(pad "37" smd rect
			(at -1.089914 -2.899918 180)
			(size 0.2286 0.6096)
			(layers "F.Cu" "F.Mask" "F.Paste")
			(net "PVDDCR_CPU0_P1_LSET5")
		)
		(pad "38" smd rect
			(at -1.540002 -2.899918 180)
			(size 0.2286 0.6096)
			(layers "F.Cu" "F.Mask" "F.Paste")
			(net "PVDDCR_CPU0_P1_IMON5")
		)
		(pad "39" smd rect
			(at -1.99009 -2.899918 180)
			(size 0.2286 0.6096)
			(layers "F.Cu" "F.Mask" "F.Paste")
			(net "PVDDCR_CPU0_P1_VCCS")
		)
		(pad "40" smd rect
			(at -0.87503 -1.27508 180)
			(size 1.7526 1.9558)
			(layers "F.Cu" "F.Mask" "F.Paste")
			(net "GND")
		)
		(pad "41" smd rect
			(at -1.525016 0.249936 90)
			(size 0.3048 0.4572)
			(layers "F.Cu" "F.Mask" "F.Paste")
			(net "NC_PVDDCR_CPU0_P1_GL2_5")
		)
		(zone
			(layer "F.Cu")
			(hatch none 0.5)
			(connect_pads
				(clearance 0)
			)
			(min_thickness 0.25)
			(keepout
				(tracks not_allowed)
				(vias allowed)
				(pads allowed)
				(copperpour not_allowed)
				(footprints allowed)
			)
			(placement
				(enabled no)
				(sheetname "")
			)
			(fill
				(thermal_gap 0.5)
				(thermal_bridge_width 0.5)
				(island_removal_mode 0)
			)
			(polygon
				(pts
					(xy 76.461112 -180.170074) (xy 76.461112 -179.87645) (xy 71.460868 -179.87645) (xy 71.460868 -180.170074)
					(xy 71.75119 -180.170074) (xy 76.17079 -180.170074)
				)
			)
		)
		(zone
			(layer "F.Cu")
			(hatch none 0.5)
			(connect_pads
				(clearance 0)
			)
			(min_thickness 0.25)
			(keepout
				(tracks not_allowed)
				(vias allowed)
				(pads allowed)
				(copperpour not_allowed)
				(footprints allowed)
			)
			(placement
				(enabled no)
				(sheetname "")
			)
			(fill
				(thermal_gap 0.5)
				(thermal_bridge_width 0.5)
				(island_removal_mode 0)
			)
			(polygon
				(pts
					(xy 73.90892 -177.37328) (xy 73.90892 -175.321976) (xy 75.76312 -175.321976) (xy 75.76312 -175.563022)
					(xy 76.005436 -175.563022) (xy 76.005436 -175.081438) (xy 72.126348 -175.081438) (xy 72.126348 -175.26635)
					(xy 73.617582 -175.26635) (xy 73.617582 -177.42535) (xy 71.460868 -177.42535) (xy 71.460868 -177.675032)
					(xy 73.607168 -177.675032)
				)
			)
		)
	)
)
